(kicad_pcb
	(version 20260206)
	(generator "pcbnew")
	(generator_version "10.0")
	(general
		(thickness 1.6)
		(legacy_teardrops no)
	)
	(paper "A4")
	(title_block
		(title "Wiwynn_Tioga_Pass_MB.brd")
		(comment 1 "Tioga Pass / footprint 431 of 4770 (J4A1), pads 244-291 of 291")
	)
	(layers
		(0 "F.Cu" signal "TOP")
		(4 "In1.Cu" signal "L2GND")
		(6 "In2.Cu" signal "L3")
		(8 "In3.Cu" signal "L4GND")
		(10 "In4.Cu" signal "L5")
		(12 "In5.Cu" signal "L6GND")
		(14 "In6.Cu" signal "L7VCC")
		(16 "In7.Cu" signal "L8VCC")
		(18 "In8.Cu" signal "L9GND")
		(20 "In9.Cu" signal "L10")
		(22 "In10.Cu" signal "L11GND")
		(24 "In11.Cu" signal "L12")
		(26 "In12.Cu" signal "L13GND")
		(2 "B.Cu" signal "BOTTOM")
		(9 "F.Adhes" user "F.Adhesive")
		(11 "B.Adhes" user "B.Adhesive")
		(13 "F.Paste" user "Package Geometry/Pastemask Top")
		(15 "B.Paste" user "Package Geometry/Pastemask Bottom")
		(5 "F.SilkS" user "Ref Des/Silkscreen Top")
		(7 "B.SilkS" user "Ref Des/Silkscreen Bottom")
		(1 "F.Mask" user "Board Geometry/Soldermask Top")
		(3 "B.Mask" user "Board Geometry/Soldermask Bottom")
		(17 "Dwgs.User" user "User.Drawings")
		(19 "Cmts.User" user "User.Comments")
		(21 "Eco1.User" user "User.Eco1")
		(23 "Eco2.User" user "User.Eco2")
		(25 "Edge.Cuts" user "Board Geometry/Outline")
		(27 "Margin" user)
		(31 "F.CrtYd" user "Package Geometry/Place Bound Top")
		(29 "B.CrtYd" user "Package Geometry/Place Bound Bottom")
		(35 "F.Fab" user "Ref Des/Assembly Top")
		(33 "B.Fab" user "Ref Des/Assembly Bottom")
	)
	(footprint ""
		(layer "F.Cu")
		(at 194.700398 -152.273 90)
		(property "Reference" "J4A1"
			(at -2.699512 42.53611 0)
			(unlocked yes)
			(layer "F.SilkS")
			(effects
				(font
					(size 0.7874 0.5842)
					(thickness 0.1524)
				)
				(justify left)
			)
		)
		(property "Value" ""
			(at 0 0 90)
			(layer "F.Fab")
			(effects
				(font
					(size 1.27 1.27)
				)
			)
		)
		(duplicate_pad_numbers_are_jumpers no)
		(pad "241" smd rect
			(at 4.59994 86.700106 90)
			(size 1.8034 0.508)
			(layers "F.Cu" "F.Mask" "F.Paste")
			(net "GND")
		)
		(pad "242" smd rect
			(at 4.59994 87.54999 90)
			(size 1.8034 0.508)
			(layers "F.Cu" "F.Mask" "F.Paste")
			(net "M_F_DQ<32>")
		)
		(pad "243" smd rect
			(at 4.59994 88.399874 90)
			(size 1.8034 0.508)
			(layers "F.Cu" "F.Mask" "F.Paste")
			(net "GND")
		)
		(pad "244" smd rect
			(at 4.59994 89.250012 90)
			(size 1.8034 0.508)
			(layers "F.Cu" "F.Mask" "F.Paste")
			(net "M_F_DQS_DN<4>")
		)
		(pad "245" smd rect
			(at 4.59994 90.099896 90)
			(size 1.8034 0.508)
			(layers "F.Cu" "F.Mask" "F.Paste")
			(net "M_F_DQS_DP<4>")
		)
		(pad "246" smd rect
			(at 4.59994 90.950034 90)
			(size 1.8034 0.508)
			(layers "F.Cu" "F.Mask" "F.Paste")
			(net "GND")
		)
		(pad "247" smd rect
			(at 4.59994 91.799918 90)
			(size 1.8034 0.508)
			(layers "F.Cu" "F.Mask" "F.Paste")
			(net "M_F_DQ<38>")
		)
		(pad "248" smd rect
			(at 4.59994 92.650056 90)
			(size 1.8034 0.508)
			(layers "F.Cu" "F.Mask" "F.Paste")
			(net "GND")
		)
		(pad "249" smd rect
			(at 4.59994 93.49994 90)
			(size 1.8034 0.508)
			(layers "F.Cu" "F.Mask" "F.Paste")
			(net "M_F_DQ<34>")
		)
		(pad "250" smd rect
			(at 4.59994 94.350078 90)
			(size 1.8034 0.508)
			(layers "F.Cu" "F.Mask" "F.Paste")
			(net "GND")
		)
		(pad "251" smd rect
			(at 4.59994 95.199962 90)
			(size 1.8034 0.508)
			(layers "F.Cu" "F.Mask" "F.Paste")
			(net "M_F_DQ<44>")
		)
		(pad "252" smd rect
			(at 4.59994 96.0501 90)
			(size 1.8034 0.508)
			(layers "F.Cu" "F.Mask" "F.Paste")
			(net "GND")
		)
		(pad "253" smd rect
			(at 4.59994 96.899984 90)
			(size 1.8034 0.508)
			(layers "F.Cu" "F.Mask" "F.Paste")
			(net "M_F_DQ<40>")
		)
		(pad "254" smd rect
			(at 4.59994 97.750122 90)
			(size 1.8034 0.508)
			(layers "F.Cu" "F.Mask" "F.Paste")
			(net "GND")
		)
		(pad "255" smd rect
			(at 4.59994 98.600006 90)
			(size 1.8034 0.508)
			(layers "F.Cu" "F.Mask" "F.Paste")
			(net "M_F_DQS_DN<5>")
		)
		(pad "256" smd rect
			(at 4.59994 99.44989 90)
			(size 1.8034 0.508)
			(layers "F.Cu" "F.Mask" "F.Paste")
			(net "M_F_DQS_DP<5>")
		)
		(pad "257" smd rect
			(at 4.59994 100.300028 90)
			(size 1.8034 0.508)
			(layers "F.Cu" "F.Mask" "F.Paste")
			(net "GND")
		)
		(pad "258" smd rect
			(at 4.59994 101.149912 90)
			(size 1.8034 0.508)
			(layers "F.Cu" "F.Mask" "F.Paste")
			(net "M_F_DQ<46>")
		)
		(pad "259" smd rect
			(at 4.59994 102.00005 90)
			(size 1.8034 0.508)
			(layers "F.Cu" "F.Mask" "F.Paste")
			(net "GND")
		)
		(pad "260" smd rect
			(at 4.59994 102.849934 90)
			(size 1.8034 0.508)
			(layers "F.Cu" "F.Mask" "F.Paste")
			(net "M_F_DQ<42>")
		)
		(pad "261" smd rect
			(at 4.59994 103.700072 90)
			(size 1.8034 0.508)
			(layers "F.Cu" "F.Mask" "F.Paste")
			(net "GND")
		)
		(pad "262" smd rect
			(at 4.59994 104.549956 90)
			(size 1.8034 0.508)
			(layers "F.Cu" "F.Mask" "F.Paste")
			(net "M_F_DQ<52>")
		)
		(pad "263" smd rect
			(at 4.59994 105.400094 90)
			(size 1.8034 0.508)
			(layers "F.Cu" "F.Mask" "F.Paste")
			(net "GND")
		)
		(pad "264" smd rect
			(at 4.59994 106.249978 90)
			(size 1.8034 0.508)
			(layers "F.Cu" "F.Mask" "F.Paste")
			(net "M_F_DQ<48>")
		)
		(pad "265" smd rect
			(at 4.59994 107.100116 90)
			(size 1.8034 0.508)
			(layers "F.Cu" "F.Mask" "F.Paste")
			(net "GND")
		)
		(pad "266" smd rect
			(at 4.59994 107.95 90)
			(size 1.8034 0.508)
			(layers "F.Cu" "F.Mask" "F.Paste")
			(net "M_F_DQS_DN<6>")
		)
		(pad "267" smd rect
			(at 4.59994 108.799884 90)
			(size 1.8034 0.508)
			(layers "F.Cu" "F.Mask" "F.Paste")
			(net "M_F_DQS_DP<6>")
		)
		(pad "268" smd rect
			(at 4.59994 109.650022 90)
			(size 1.8034 0.508)
			(layers "F.Cu" "F.Mask" "F.Paste")
			(net "GND")
		)
		(pad "269" smd rect
			(at 4.59994 110.499906 90)
			(size 1.8034 0.508)
			(layers "F.Cu" "F.Mask" "F.Paste")
			(net "M_F_DQ<54>")
		)
		(pad "270" smd rect
			(at 4.59994 111.350044 90)
			(size 1.8034 0.508)
			(layers "F.Cu" "F.Mask" "F.Paste")
			(net "GND")
		)
		(pad "271" smd rect
			(at 4.59994 112.199928 90)
			(size 1.8034 0.508)
			(layers "F.Cu" "F.Mask" "F.Paste")
			(net "M_F_DQ<50>")
		)
		(pad "272" smd rect
			(at 4.59994 113.050066 90)
			(size 1.8034 0.508)
			(layers "F.Cu" "F.Mask" "F.Paste")
			(net "GND")
		)
		(pad "273" smd rect
			(at 4.59994 113.89995 90)
			(size 1.8034 0.508)
			(layers "F.Cu" "F.Mask" "F.Paste")
			(net "M_F_DQ<60>")
		)
		(pad "274" smd rect
			(at 4.59994 114.750088 90)
			(size 1.8034 0.508)
			(layers "F.Cu" "F.Mask" "F.Paste")
			(net "GND")
		)
		(pad "275" smd rect
			(at 4.59994 115.599972 90)
			(size 1.8034 0.508)
			(layers "F.Cu" "F.Mask" "F.Paste")
			(net "M_F_DQ<56>")
		)
		(pad "276" smd rect
			(at 4.59994 116.45011 90)
			(size 1.8034 0.508)
			(layers "F.Cu" "F.Mask" "F.Paste")
			(net "GND")
		)
		(pad "277" smd rect
			(at 4.59994 117.299994 90)
			(size 1.8034 0.508)
			(layers "F.Cu" "F.Mask" "F.Paste")
			(net "M_F_DQS_DN<7>")
		)
		(pad "278" smd rect
			(at 4.59994 118.149878 90)
			(size 1.8034 0.508)
			(layers "F.Cu" "F.Mask" "F.Paste")
			(net "M_F_DQS_DP<7>")
		)
		(pad "279" smd rect
			(at 4.59994 119.000016 90)
			(size 1.8034 0.508)
			(layers "F.Cu" "F.Mask" "F.Paste")
			(net "GND")
		)
		(pad "280" smd rect
			(at 4.59994 119.8499 90)
			(size 1.8034 0.508)
			(layers "F.Cu" "F.Mask" "F.Paste")
			(net "M_F_DQ<62>")
		)
		(pad "281" smd rect
			(at 4.59994 120.700038 90)
			(size 1.8034 0.508)
			(layers "F.Cu" "F.Mask" "F.Paste")
			(net "GND")
		)
		(pad "282" smd rect
			(at 4.59994 121.549922 90)
			(size 1.8034 0.508)
			(layers "F.Cu" "F.Mask" "F.Paste")
			(net "M_F_DQ<58>")
		)
		(pad "283" smd rect
			(at 4.59994 122.40006 90)
			(size 1.8034 0.508)
			(layers "F.Cu" "F.Mask" "F.Paste")
			(net "GND")
		)
		(pad "284" smd rect
			(at 4.59994 123.249944 90)
			(size 1.8034 0.508)
			(layers "F.Cu" "F.Mask" "F.Paste")
			(net "PVPP_DEF")
		)
		(pad "285" smd rect
			(at 4.59994 124.100082 90)
			(size 1.8034 0.508)
			(layers "F.Cu" "F.Mask" "F.Paste")
			(net "SMB_DDR_DEF_VPP_SDA")
		)
		(pad "286" smd rect
			(at 4.59994 124.949966 90)
			(size 1.8034 0.508)
			(layers "F.Cu" "F.Mask" "F.Paste")
			(net "PVPP_DEF")
		)
		(pad "287" smd rect
			(at 4.59994 125.800104 90)
			(size 1.8034 0.508)
			(layers "F.Cu" "F.Mask" "F.Paste")
			(net "PVPP_DEF")
		)
		(pad "288" smd rect
			(at 4.59994 126.649988 90)
			(size 1.8034 0.508)
			(layers "F.Cu" "F.Mask" "F.Paste")
			(net "PVPP_DEF")
		)
	)
)
